(kicad_pcb
	(version 20260206)
	(generator "pcbnew")
	(generator_version "10.0")
	(general
		(thickness 1.6)
		(legacy_teardrops no)
	)
	(paper "A4")
	(title_block
		(title "v1-chassis-manager — T6M_CM_d_v01_1031_1645.brd")
		(comment 1 "Open CloudServer (Microsoft) / footprints 111-120 of 2512")
	)
	(layers
		(0 "F.Cu" signal "TOP")
		(4 "In1.Cu" signal "GND1")
		(6 "In2.Cu" signal "IN1")
		(8 "In3.Cu" signal "VCC1")
		(10 "In4.Cu" signal "VCC2")
		(12 "In5.Cu" signal "GND2")
		(14 "In6.Cu" signal "IN2")
		(16 "In7.Cu" signal "IN3")
		(18 "In8.Cu" signal "GND3")
		(2 "B.Cu" signal "BOTTOM")
		(9 "F.Adhes" user "F.Adhesive")
		(11 "B.Adhes" user "B.Adhesive")
		(13 "F.Paste" user "Package Geometry/Pastemask Top")
		(15 "B.Paste" user "Package Geometry/Pastemask Bottom")
		(5 "F.SilkS" user "Ref Des/Silkscreen Top")
		(7 "B.SilkS" user "Ref Des/Silkscreen Bottom")
		(1 "F.Mask" user "Board Geometry/Soldermask Top")
		(3 "B.Mask" user "Board Geometry/Soldermask Bottom")
		(17 "Dwgs.User" user "User.Drawings")
		(19 "Cmts.User" user "User.Comments")
		(21 "Eco1.User" user "User.Eco1")
		(23 "Eco2.User" user "User.Eco2")
		(25 "Edge.Cuts" user "Board Geometry/Outline")
		(27 "Margin" user)
		(31 "F.CrtYd" user "Package Geometry/Place Bound Top")
		(29 "B.CrtYd" user "Package Geometry/Place Bound Bottom")
		(35 "F.Fab" user "Ref Des/Assembly Top")
		(33 "B.Fab" user "Ref Des/Assembly Bottom")
	)
	(footprint ""
		(layer "F.Cu")
		(at 35.669728 -81.036922)
		(property "Reference" "R41"
			(at -4.58851 -0.106934 0)
			(unlocked yes)
			(layer "F.SilkS")
			(effects
				(font
					(size 0.7874 0.5842)
					(thickness 0.1524)
				)
				(justify left)
			)
		)
		(property "Value" ""
			(at 0 0 0)
			(layer "F.Fab")
			(effects
				(font
					(size 1.27 1.27)
				)
			)
		)
		(duplicate_pad_numbers_are_jumpers no)
		(fp_line
			(start -0.7874 -0.4064)
			(end 0.7874 -0.4064)
			(stroke
				(width 0.1524)
				(type default)
			)
			(layer "F.SilkS")
		)
		(fp_line
			(start -0.7874 0.4064)
			(end -0.7874 -0.4064)
			(stroke
				(width 0.1524)
				(type default)
			)
			(layer "F.SilkS")
		)
		(fp_line
			(start 0.7874 -0.4064)
			(end 0.7874 0.4064)
			(stroke
				(width 0.1524)
				(type default)
			)
			(layer "F.SilkS")
		)
		(fp_line
			(start 0.7874 0.4064)
			(end -0.7874 0.4064)
			(stroke
				(width 0.1524)
				(type default)
			)
			(layer "F.SilkS")
		)
		(fp_poly
			(pts
				(xy -0.508 0.2794) (xy -0.508 0.2286) (xy -0.635 0.2286) (xy -0.635 -0.254) (xy -0.5334 -0.254)
				(xy -0.5334 -0.2794) (xy 0.5334 -0.2794) (xy 0.5334 -0.254) (xy 0.635 -0.254) (xy 0.635 0.254) (xy 0.5334 0.254)
				(xy 0.5334 0.2794)
			)
			(stroke
				(width 0)
				(type default)
			)
			(fill no)
			(layer "F.CrtYd")
		)
		(pad "1" smd rect
			(at 0.40005 0)
			(size 0.4572 0.508)
			(layers "F.Cu" "F.Mask" "F.Paste")
			(net "PD_CPU_NODE1_W1")
		)
		(pad "2" smd rect
			(at -0.40005 0)
			(size 0.4572 0.508)
			(layers "F.Cu" "F.Mask" "F.Paste")
			(net "GND")
		)
	)
	(footprint ""
		(layer "F.Cu")
		(at 13.894562 -29.850334 90)
		(property "Reference" "C545"
			(at -1.276604 -0.944118 90)
			(unlocked yes)
			(layer "F.SilkS")
			(effects
				(font
					(size 0.7874 0.5842)
					(thickness 0.1524)
				)
				(justify left)
			)
		)
		(property "Value" ""
			(at 0 0 90)
			(layer "F.Fab")
			(effects
				(font
					(size 1.27 1.27)
				)
			)
		)
		(duplicate_pad_numbers_are_jumpers no)
		(fp_line
			(start 0.7874 -0.4064)
			(end 0.7874 0.4064)
			(stroke
				(width 0.1524)
				(type default)
			)
			(layer "F.SilkS")
		)
		(fp_line
			(start -0.7874 -0.4064)
			(end 0.7874 -0.4064)
			(stroke
				(width 0.1524)
				(type default)
			)
			(layer "F.SilkS")
		)
		(fp_line
			(start 0 0.381)
			(end 0 -0.381)
			(stroke
				(width 0.1524)
				(type default)
			)
			(layer "F.SilkS")
		)
		(fp_line
			(start 0.7874 0.4064)
			(end -0.7874 0.4064)
			(stroke
				(width 0.1524)
				(type default)
			)
			(layer "F.SilkS")
		)
		(fp_line
			(start -0.7874 0.4064)
			(end -0.7874 -0.4064)
			(stroke
				(width 0.1524)
				(type default)
			)
			(layer "F.SilkS")
		)
		(fp_poly
			(pts
				(xy -0.5334 0.254) (xy -0.635 0.254) (xy -0.635 0.2286) (xy -0.635 -0.254) (xy -0.5334 -0.254) (xy -0.5334 -0.2794)
				(xy 0.5334 -0.2794) (xy 0.5334 -0.254) (xy 0.635 -0.254) (xy 0.635 0.254) (xy 0.5334 0.254) (xy 0.5334 0.2794)
				(xy -0.508 0.2794) (xy -0.5334 0.2794)
			)
			(stroke
				(width 0)
				(type default)
			)
			(fill no)
			(layer "F.CrtYd")
		)
		(pad "1" smd rect
			(at 0.40005 0 90)
			(size 0.4572 0.508)
			(layers "F.Cu" "F.Mask" "F.Paste")
			(net "GND")
		)
		(pad "2" smd rect
			(at -0.40005 0 90)
			(size 0.4572 0.508)
			(layers "F.Cu" "F.Mask" "F.Paste")
			(net "N54251541")
		)
	)
	(footprint ""
		(layer "F.Cu")
		(at 30.58287 -130.513074)
		(property "Reference" "PR17"
			(at -1.295654 -3.38074 0)
			(unlocked yes)
			(layer "F.SilkS")
			(effects
				(font
					(size 0.7874 0.5842)
					(thickness 0.1524)
				)
				(justify left)
			)
		)
		(property "Value" ""
			(at 0 0 0)
			(layer "F.Fab")
			(effects
				(font
					(size 1.27 1.27)
				)
			)
		)
		(duplicate_pad_numbers_are_jumpers no)
		(fp_line
			(start -0.7874 -0.4064)
			(end 0.7874 -0.4064)
			(stroke
				(width 0.1524)
				(type default)
			)
			(layer "F.SilkS")
		)
		(fp_line
			(start -0.7874 0.4064)
			(end -0.7874 -0.4064)
			(stroke
				(width 0.1524)
				(type default)
			)
			(layer "F.SilkS")
		)
		(fp_line
			(start 0.7874 -0.4064)
			(end 0.7874 0.4064)
			(stroke
				(width 0.1524)
				(type default)
			)
			(layer "F.SilkS")
		)
		(fp_line
			(start 0.7874 0.4064)
			(end -0.7874 0.4064)
			(stroke
				(width 0.1524)
				(type default)
			)
			(layer "F.SilkS")
		)
		(fp_poly
			(pts
				(xy -0.508 0.2794) (xy -0.508 0.2286) (xy -0.635 0.2286) (xy -0.635 -0.254) (xy -0.5334 -0.254)
				(xy -0.5334 -0.2794) (xy 0.5334 -0.2794) (xy 0.5334 -0.254) (xy 0.635 -0.254) (xy 0.635 0.254) (xy 0.5334 0.254)
				(xy 0.5334 0.2794)
			)
			(stroke
				(width 0)
				(type default)
			)
			(fill no)
			(layer "F.CrtYd")
		)
		(pad "1" smd rect
			(at 0.40005 0)
			(size 0.4572 0.508)
			(layers "F.Cu" "F.Mask" "F.Paste")
			(net "GND")
		)
		(pad "2" smd rect
			(at -0.40005 0)
			(size 0.4572 0.508)
			(layers "F.Cu" "F.Mask" "F.Paste")
			(net "P1V538_BMC_NODE1_ADJ")
		)
	)
	(footprint ""
		(layer "F.Cu")
		(at 70.1548 -100.254562 180)
		(property "Reference" "R1092"
			(at 1.197102 3.21691 0)
			(unlocked yes)
			(layer "F.SilkS")
			(effects
				(font
					(size 0.7874 0.5842)
					(thickness 0.1524)
				)
				(justify left)
			)
		)
		(property "Value" ""
			(at 0 0 180)
			(layer "F.Fab")
			(effects
				(font
					(size 1.27 1.27)
				)
			)
		)
		(duplicate_pad_numbers_are_jumpers no)
		(fp_line
			(start 0.7874 0.4064)
			(end -0.7874 0.4064)
			(stroke
				(width 0.1524)
				(type default)
			)
			(layer "F.SilkS")
		)
		(fp_line
			(start 0.7874 -0.4064)
			(end 0.7874 0.4064)
			(stroke
				(width 0.1524)
				(type default)
			)
			(layer "F.SilkS")
		)
		(fp_line
			(start -0.7874 0.4064)
			(end -0.7874 -0.4064)
			(stroke
				(width 0.1524)
				(type default)
			)
			(layer "F.SilkS")
		)
		(fp_line
			(start -0.7874 -0.4064)
			(end 0.7874 -0.4064)
			(stroke
				(width 0.1524)
				(type default)
			)
			(layer "F.SilkS")
		)
		(fp_poly
			(pts
				(xy -0.508 0.2794) (xy -0.508 0.2286) (xy -0.635 0.2286) (xy -0.635 -0.254) (xy -0.5334 -0.254)
				(xy -0.5334 -0.2794) (xy 0.5334 -0.2794) (xy 0.5334 -0.254) (xy 0.635 -0.254) (xy 0.635 0.254) (xy 0.5334 0.254)
				(xy 0.5334 0.2794)
			)
			(stroke
				(width 0)
				(type default)
			)
			(fill no)
			(layer "F.CrtYd")
		)
		(pad "1" smd rect
			(at 0.40005 0 180)
			(size 0.4572 0.508)
			(layers "F.Cu" "F.Mask" "F.Paste")
			(net "FM_CPLD_NODE1_P1V8_SUS_EN_G")
		)
		(pad "2" smd rect
			(at -0.40005 0 180)
			(size 0.4572 0.508)
			(layers "F.Cu" "F.Mask" "F.Paste")
			(net "P3V3_STB_NODE1")
		)
	)
	(footprint ""
		(layer "F.Cu")
		(at 109.163866 -128.859026)
		(property "Reference" "PC96"
			(at -8.975852 3.389122 0)
			(unlocked yes)
			(layer "F.SilkS")
			(effects
				(font
					(size 0.7874 0.5842)
					(thickness 0.1524)
				)
				(justify left)
			)
		)
		(property "Value" ""
			(at 0 0 0)
			(layer "F.Fab")
			(effects
				(font
					(size 1.27 1.27)
				)
			)
		)
		(duplicate_pad_numbers_are_jumpers no)
		(fp_line
			(start -0.7874 -0.4064)
			(end 0.7874 -0.4064)
			(stroke
				(width 0.1524)
				(type default)
			)
			(layer "F.SilkS")
		)
		(fp_line
			(start -0.7874 0.4064)
			(end -0.7874 -0.4064)
			(stroke
				(width 0.1524)
				(type default)
			)
			(layer "F.SilkS")
		)
		(fp_line
			(start 0 0.381)
			(end 0 -0.381)
			(stroke
				(width 0.1524)
				(type default)
			)
			(layer "F.SilkS")
		)
		(fp_line
			(start 0.7874 -0.4064)
			(end 0.7874 0.4064)
			(stroke
				(width 0.1524)
				(type default)
			)
			(layer "F.SilkS")
		)
		(fp_line
			(start 0.7874 0.4064)
			(end -0.7874 0.4064)
			(stroke
				(width 0.1524)
				(type default)
			)
			(layer "F.SilkS")
		)
		(fp_poly
			(pts
				(xy -0.5334 0.254) (xy -0.635 0.254) (xy -0.635 0.2286) (xy -0.635 -0.254) (xy -0.5334 -0.254) (xy -0.5334 -0.2794)
				(xy 0.5334 -0.2794) (xy 0.5334 -0.254) (xy 0.635 -0.254) (xy 0.635 0.254) (xy 0.5334 0.254) (xy 0.5334 0.2794)
				(xy -0.508 0.2794) (xy -0.5334 0.2794)
			)
			(stroke
				(width 0)
				(type default)
			)
			(fill no)
			(layer "F.CrtYd")
		)
		(pad "1" smd rect
			(at 0.40005 0)
			(size 0.4572 0.508)
			(layers "F.Cu" "F.Mask" "F.Paste")
			(net "VR_PVCCP_NODE1_BOOT1")
		)
		(pad "2" smd rect
			(at -0.40005 0)
			(size 0.4572 0.508)
			(layers "F.Cu" "F.Mask" "F.Paste")
			(net "VR_PVCCP_NODE1_PHASE1")
		)
	)
	(footprint ""
		(layer "F.Cu")
		(at 56.191912 -100.35921 -90)
		(property "Reference" "R196"
			(at -1.014222 -0.04064 90)
			(unlocked yes)
			(layer "F.SilkS")
			(effects
				(font
					(size 0.7874 0.5842)
					(thickness 0.1524)
				)
				(justify left)
			)
		)
		(property "Value" ""
			(at 0 0 270)
			(layer "F.Fab")
			(effects
				(font
					(size 1.27 1.27)
				)
			)
		)
		(duplicate_pad_numbers_are_jumpers no)
		(fp_line
			(start -0.7874 0.4064)
			(end -0.7874 -0.4064)
			(stroke
				(width 0.1524)
				(type default)
			)
			(layer "F.SilkS")
		)
		(fp_line
			(start 0.7874 0.4064)
			(end -0.7874 0.4064)
			(stroke
				(width 0.1524)
				(type default)
			)
			(layer "F.SilkS")
		)
		(fp_line
			(start -0.7874 -0.4064)
			(end 0.7874 -0.4064)
			(stroke
				(width 0.1524)
				(type default)
			)
			(layer "F.SilkS")
		)
		(fp_line
			(start 0.7874 -0.4064)
			(end 0.7874 0.4064)
			(stroke
				(width 0.1524)
				(type default)
			)
			(layer "F.SilkS")
		)
		(fp_poly
			(pts
				(xy -0.508 0.2794) (xy -0.508 0.2286) (xy -0.635 0.2286) (xy -0.635 -0.254) (xy -0.5334 -0.254)
				(xy -0.5334 -0.2794) (xy 0.5334 -0.2794) (xy 0.5334 -0.254) (xy 0.635 -0.254) (xy 0.635 0.254) (xy 0.5334 0.254)
				(xy 0.5334 0.2794)
			)
			(stroke
				(width 0)
				(type default)
			)
			(fill no)
			(layer "F.CrtYd")
		)
		(pad "1" smd rect
			(at 0.40005 0 270)
			(size 0.4572 0.508)
			(layers "F.Cu" "F.Mask" "F.Paste")
			(net "P3V3_NODE1")
		)
		(pad "2" smd rect
			(at -0.40005 0 270)
			(size 0.4572 0.508)
			(layers "F.Cu" "F.Mask" "F.Paste")
			(net "PU_EMC1428_NODE1_TRIP")
		)
	)
	(footprint ""
		(layer "F.Cu")
		(at 126.64694 -165.259004 180)
		(property "Reference" "R679"
			(at 1.356868 4.558792 0)
			(unlocked yes)
			(layer "F.SilkS")
			(effects
				(font
					(size 0.7874 0.5842)
					(thickness 0.1524)
				)
				(justify left)
			)
		)
		(property "Value" ""
			(at 0 0 180)
			(layer "F.Fab")
			(effects
				(font
					(size 1.27 1.27)
				)
			)
		)
		(duplicate_pad_numbers_are_jumpers no)
		(fp_line
			(start 0.7874 0.4064)
			(end -0.7874 0.4064)
			(stroke
				(width 0.1524)
				(type default)
			)
			(layer "F.SilkS")
		)
		(fp_line
			(start 0.7874 -0.4064)
			(end 0.7874 0.4064)
			(stroke
				(width 0.1524)
				(type default)
			)
			(layer "F.SilkS")
		)
		(fp_line
			(start -0.7874 0.4064)
			(end -0.7874 -0.4064)
			(stroke
				(width 0.1524)
				(type default)
			)
			(layer "F.SilkS")
		)
		(fp_line
			(start -0.7874 -0.4064)
			(end 0.7874 -0.4064)
			(stroke
				(width 0.1524)
				(type default)
			)
			(layer "F.SilkS")
		)
		(fp_poly
			(pts
				(xy -0.508 0.2794) (xy -0.508 0.2286) (xy -0.635 0.2286) (xy -0.635 -0.254) (xy -0.5334 -0.254)
				(xy -0.5334 -0.2794) (xy 0.5334 -0.2794) (xy 0.5334 -0.254) (xy 0.635 -0.254) (xy 0.635 0.254) (xy 0.5334 0.254)
				(xy 0.5334 0.2794)
			)
			(stroke
				(width 0)
				(type default)
			)
			(fill no)
			(layer "F.CrtYd")
		)
		(pad "1" smd rect
			(at 0.40005 0 180)
			(size 0.4572 0.508)
			(layers "F.Cu" "F.Mask" "F.Paste")
			(net "CPLD123_RSV1")
		)
		(pad "2" smd rect
			(at -0.40005 0 180)
			(size 0.4572 0.508)
			(layers "F.Cu" "F.Mask" "F.Paste")
			(net "CPLD3_RSV1")
		)
	)
	(footprint ""
		(layer "F.Cu")
		(at 48.24476 -188.126624 90)
		(property "Reference" "R851"
			(at 4.548886 0.205232 90)
			(unlocked yes)
			(layer "F.SilkS")
			(effects
				(font
					(size 0.7874 0.5842)
					(thickness 0.1524)
				)
				(justify left)
			)
		)
		(property "Value" ""
			(at 0 0 90)
			(layer "F.Fab")
			(effects
				(font
					(size 1.27 1.27)
				)
			)
		)
		(duplicate_pad_numbers_are_jumpers no)
		(fp_line
			(start 0.7874 -0.4064)
			(end 0.7874 0.4064)
			(stroke
				(width 0.1524)
				(type default)
			)
			(layer "F.SilkS")
		)
		(fp_line
			(start -0.7874 -0.4064)
			(end 0.7874 -0.4064)
			(stroke
				(width 0.1524)
				(type default)
			)
			(layer "F.SilkS")
		)
		(fp_line
			(start 0.7874 0.4064)
			(end -0.7874 0.4064)
			(stroke
				(width 0.1524)
				(type default)
			)
			(layer "F.SilkS")
		)
		(fp_line
			(start -0.7874 0.4064)
			(end -0.7874 -0.4064)
			(stroke
				(width 0.1524)
				(type default)
			)
			(layer "F.SilkS")
		)
		(fp_poly
			(pts
				(xy -0.508 0.2794) (xy -0.508 0.2286) (xy -0.635 0.2286) (xy -0.635 -0.254) (xy -0.5334 -0.254)
				(xy -0.5334 -0.2794) (xy 0.5334 -0.2794) (xy 0.5334 -0.254) (xy 0.635 -0.254) (xy 0.635 0.254) (xy 0.5334 0.254)
				(xy 0.5334 0.2794)
			)
			(stroke
				(width 0)
				(type default)
			)
			(fill no)
			(layer "F.CrtYd")
		)
		(pad "1" smd rect
			(at 0.40005 0 90)
			(size 0.4572 0.508)
			(layers "F.Cu" "F.Mask" "F.Paste")
			(net "PSU5_AC_OK_R")
		)
		(pad "2" smd rect
			(at -0.40005 0 90)
			(size 0.4572 0.508)
			(layers "F.Cu" "F.Mask" "F.Paste")
			(net "GND")
		)
	)
	(footprint ""
		(layer "F.Cu")
		(at 137.730992 -25.421844 -90)
		(property "Reference" "C491"
			(at 8.86841 -4.51993 90)
			(unlocked yes)
			(layer "F.SilkS")
			(effects
				(font
					(size 0.7874 0.5842)
					(thickness 0.1524)
				)
			)
		)
		(property "Value" ""
			(at 0 0 270)
			(layer "F.Fab")
			(effects
				(font
					(size 1.27 1.27)
				)
			)
		)
		(duplicate_pad_numbers_are_jumpers no)
		(fp_line
			(start -1.2954 0.5842)
			(end -1.2954 -0.5842)
			(stroke
				(width 0.1524)
				(type default)
			)
			(layer "F.SilkS")
		)
		(fp_line
			(start 1.2954 0.5842)
			(end -1.2954 0.5842)
			(stroke
				(width 0.1524)
				(type default)
			)
			(layer "F.SilkS")
		)
		(fp_line
			(start -1.2954 -0.5842)
			(end 1.2954 -0.5842)
			(stroke
				(width 0.1524)
				(type default)
			)
			(layer "F.SilkS")
		)
		(fp_line
			(start 0 -0.5842)
			(end 0 0.5842)
			(stroke
				(width 0.1524)
				(type default)
			)
			(layer "F.SilkS")
		)
		(fp_line
			(start 1.2954 -0.5842)
			(end 1.2954 0.5842)
			(stroke
				(width 0.1524)
				(type default)
			)
			(layer "F.SilkS")
		)
		(fp_poly
			(pts
				(xy 0.8636 -0.4572) (xy 0.8636 -0.3556) (xy 1.143 -0.3556) (xy 1.143 0.3556) (xy 0.8636 0.3556)
				(xy 0.8636 0.4572) (xy -0.8636 0.4572) (xy -0.8636 0.3556) (xy -1.143 0.3556) (xy -1.143 -0.3556)
				(xy -0.8636 -0.3556) (xy -0.8636 -0.4572)
			)
			(stroke
				(width 0)
				(type default)
			)
			(fill no)
			(layer "F.CrtYd")
		)
		(fp_line
			(start -0.884936 0.504952)
			(end -0.884936 -0.504952)
			(stroke
				(width 0.1)
				(type default)
			)
			(layer "F.Fab")
		)
		(fp_line
			(start 0.884936 0.504952)
			(end -0.884936 0.504952)
			(stroke
				(width 0.1)
				(type default)
			)
			(layer "F.Fab")
		)
		(fp_line
			(start -0.884936 -0.504952)
			(end 0.884936 -0.504952)
			(stroke
				(width 0.1)
				(type default)
			)
			(layer "F.Fab")
		)
		(fp_line
			(start 0.884936 -0.504952)
			(end 0.884936 0.504952)
			(stroke
				(width 0.1)
				(type default)
			)
			(layer "F.Fab")
		)
		(pad "1" smd rect
			(at 0.7366 0)
			(size 0.7112 0.8128)
			(layers "F.Cu" "F.Mask" "F.Paste")
			(net "P5V_NODE1")
		)
		(pad "2" smd rect
			(at -0.7366 0)
			(size 0.7112 0.8128)
			(layers "F.Cu" "F.Mask" "F.Paste")
			(net "GND")
		)
	)
	(footprint ""
		(layer "F.Cu")
		(at 106.426508 -177.969926 180)
		(property "Reference" "R751"
			(at 0.555498 3.196844 0)
			(unlocked yes)
			(layer "F.SilkS")
			(effects
				(font
					(size 0.7874 0.5842)
					(thickness 0.1524)
				)
				(justify left)
			)
		)
		(property "Value" ""
			(at 0 0 180)
			(layer "F.Fab")
			(effects
				(font
					(size 1.27 1.27)
				)
			)
		)
		(duplicate_pad_numbers_are_jumpers no)
		(fp_line
			(start 0.7874 0.4064)
			(end -0.7874 0.4064)
			(stroke
				(width 0.1524)
				(type default)
			)
			(layer "F.SilkS")
		)
		(fp_line
			(start 0.7874 -0.4064)
			(end 0.7874 0.4064)
			(stroke
				(width 0.1524)
				(type default)
			)
			(layer "F.SilkS")
		)
		(fp_line
			(start -0.7874 0.4064)
			(end -0.7874 -0.4064)
			(stroke
				(width 0.1524)
				(type default)
			)
			(layer "F.SilkS")
		)
		(fp_line
			(start -0.7874 -0.4064)
			(end 0.7874 -0.4064)
			(stroke
				(width 0.1524)
				(type default)
			)
			(layer "F.SilkS")
		)
		(fp_poly
			(pts
				(xy -0.508 0.2794) (xy -0.508 0.2286) (xy -0.635 0.2286) (xy -0.635 -0.254) (xy -0.5334 -0.254)
				(xy -0.5334 -0.2794) (xy 0.5334 -0.2794) (xy 0.5334 -0.254) (xy 0.635 -0.254) (xy 0.635 0.254) (xy 0.5334 0.254)
				(xy 0.5334 0.2794)
			)
			(stroke
				(width 0)
				(type default)
			)
			(fill no)
			(layer "F.CrtYd")
		)
		(pad "1" smd rect
			(at 0.40005 0 180)
			(size 0.4572 0.508)
			(layers "F.Cu" "F.Mask" "F.Paste")
			(net "N21700943")
		)
		(pad "2" smd rect
			(at -0.40005 0 180)
			(size 0.4572 0.508)
			(layers "F.Cu" "F.Mask" "F.Paste")
			(net "GND")
		)
	)
)
